(kicad_pcb
	(version 20260206)
	(generator "pcbnew")
	(generator_version "10.0")
	(general
		(thickness 1.6)
		(legacy_teardrops no)
	)
	(paper "A4")
	(title_block
		(title "peb — Lightning_PEB_BRD.brd")
		(comment 1 "Lightning (Wiwynn / Facebook NVMe JBOF) / footprints 1223-1229 of 2563")
	)
	(layers
		(0 "F.Cu" signal "TOP")
		(4 "In1.Cu" signal "L2GND")
		(6 "In2.Cu" signal "L3")
		(8 "In3.Cu" signal "L4VCC")
		(10 "In4.Cu" signal "L5VCC")
		(12 "In5.Cu" signal "L6")
		(14 "In6.Cu" signal "L7GND")
		(2 "B.Cu" signal "BOTTOM")
		(9 "F.Adhes" user "F.Adhesive")
		(11 "B.Adhes" user "B.Adhesive")
		(13 "F.Paste" user "Package Geometry/Pastemask Top")
		(15 "B.Paste" user "Package Geometry/Pastemask Bottom")
		(5 "F.SilkS" user "Ref Des/Silkscreen Top")
		(7 "B.SilkS" user "Ref Des/Silkscreen Bottom")
		(1 "F.Mask" user "Board Geometry/Soldermask Top")
		(3 "B.Mask" user "Board Geometry/Soldermask Bottom")
		(17 "Dwgs.User" user "User.Drawings")
		(19 "Cmts.User" user "User.Comments")
		(21 "Eco1.User" user "User.Eco1")
		(23 "Eco2.User" user "User.Eco2")
		(25 "Edge.Cuts" user "Board Geometry/Outline")
		(27 "Margin" user)
		(31 "F.CrtYd" user "Package Geometry/Place Bound Top")
		(29 "B.CrtYd" user "Package Geometry/Place Bound Bottom")
		(35 "F.Fab" user "Ref Des/Assembly Top")
		(33 "B.Fab" user "Ref Des/Assembly Bottom")
	)
	(footprint ""
		(layer "F.Cu")
		(at 183.992266 -212.420454 180)
		(property "Reference" "C127"
			(at 0 0 180)
			(layer "F.SilkS")
			(hide yes)
			(effects
				(font
					(size 1.27 1.27)
				)
			)
		)
		(property "Value" "SCD22U10V2KX-1GP"
			(at 1.1811 -2.7051 180)
			(unlocked yes)
			(layer "F.Fab")
			(hide yes)
			(effects
				(font
					(size 1.016 1.016)
					(thickness 0.1524)
				)
			)
		)
		(property "Device Type" "C402H22"
			(at 1.1811 -4.2291 180)
			(unlocked yes)
			(layer "F.Fab")
			(hide yes)
			(effects
				(font
					(size 1.016 1.016)
					(thickness 0.1524)
				)
			)
		)
		(duplicate_pad_numbers_are_jumpers no)
		(fp_rect
			(start -0.4318 0.9525)
			(end 0.4318 -0.9525)
			(stroke
				(width 0)
				(type default)
			)
			(fill no)
			(layer "F.CrtYd")
		)
		(fp_rect
			(start -0.4318 0.9525)
			(end 0.4318 -0.9525)
			(stroke
				(width 0)
				(type default)
			)
			(fill no)
			(layer "F.Fab")
		)
		(pad "1" smd custom
			(at 0 -0.4445 180)
			(size 0.1524 0.1524)
			(layers "F.Cu" "F.Mask" "F.Paste")
			(net "PCIE_TX_CAP_P47")
			(options
				(clearance outline)
				(anchor circle)
			)
			(primitives
				(gr_poly
					(pts
						(arc
							(start 0.3048 -0.2032)
							(mid 0.275042 -0.275042)
							(end 0.2032 -0.3048)
						)
						(arc
							(start -0.2032 -0.3048)
							(mid -0.275042 -0.275042)
							(end -0.3048 -0.2032)
						)
						(arc
							(start -0.3048 0.2032)
							(mid -0.275042 0.275042)
							(end -0.2032 0.3048)
						)
						(arc
							(start 0.2032 0.3048)
							(mid 0.275042 0.275042)
							(end 0.3048 0.2032)
						)
					)
					(width 0)
					(fill yes)
				)
			)
		)
		(pad "2" smd custom
			(at 0 0.4445 180)
			(size 0.1524 0.1524)
			(layers "F.Cu" "F.Mask" "F.Paste")
			(net "PCIE_TX_P47")
			(options
				(clearance outline)
				(anchor circle)
			)
			(primitives
				(gr_poly
					(pts
						(arc
							(start 0.3048 -0.2032)
							(mid 0.275042 -0.275042)
							(end 0.2032 -0.3048)
						)
						(arc
							(start -0.2032 -0.3048)
							(mid -0.275042 -0.275042)
							(end -0.3048 -0.2032)
						)
						(arc
							(start -0.3048 0.2032)
							(mid -0.275042 0.275042)
							(end -0.2032 0.3048)
						)
						(arc
							(start 0.2032 0.3048)
							(mid 0.275042 0.275042)
							(end 0.3048 0.2032)
						)
					)
					(width 0)
					(fill yes)
				)
			)
		)
	)
	(footprint ""
		(layer "F.Cu")
		(at 31.7754 -74.3712 180)
		(property "Reference" "PU58"
			(at 0 0 180)
			(layer "F.SilkS")
			(hide yes)
			(effects
				(font
					(size 1.27 1.27)
				)
			)
		)
		(property "Value" "SY8120ABC-GP"
			(at -0.0254 -11.9634 180)
			(unlocked yes)
			(layer "F.Fab")
			(hide yes)
			(effects
				(font
					(size 1.016 1.016)
					(thickness 0.1524)
				)
			)
		)
		(property "Device Type" "SOT-6H56"
			(at -0.0254 -13.5636 180)
			(unlocked yes)
			(layer "F.Fab")
			(hide yes)
			(effects
				(font
					(size 1.016 1.016)
					(thickness 0.1524)
				)
			)
		)
		(duplicate_pad_numbers_are_jumpers no)
		(fp_line
			(start 1.7145 0.5842)
			(end 1.7145 -0.5842)
			(stroke
				(width 0.1524)
				(type default)
			)
			(layer "F.SilkS")
		)
		(fp_line
			(start 1.7145 -0.5842)
			(end -1.9685 -0.5842)
			(stroke
				(width 0.1524)
				(type default)
			)
			(layer "F.SilkS")
		)
		(fp_line
			(start -1.5621 0)
			(end -1.9685 0.4064)
			(stroke
				(width 0.1524)
				(type default)
			)
			(layer "F.SilkS")
		)
		(fp_line
			(start -1.9685 0.5842)
			(end 1.7145 0.5842)
			(stroke
				(width 0.1524)
				(type default)
			)
			(layer "F.SilkS")
		)
		(fp_line
			(start -1.9685 0.5842)
			(end -1.9685 2.3622)
			(stroke
				(width 0.508)
				(type default)
			)
			(layer "F.SilkS")
		)
		(fp_line
			(start -1.9685 -0.4064)
			(end -1.5621 0)
			(stroke
				(width 0.1524)
				(type default)
			)
			(layer "F.SilkS")
		)
		(fp_line
			(start -1.9685 -0.5842)
			(end -1.9685 0.5842)
			(stroke
				(width 0.1524)
				(type default)
			)
			(layer "F.SilkS")
		)
		(fp_poly
			(pts
				(xy -1.27 -0.635) (xy 1.27 -0.635) (xy 1.27 0.635) (xy -1.27 0.635)
			)
			(stroke
				(width 0)
				(type default)
			)
			(fill yes)
			(layer "F.SilkS")
		)
		(fp_rect
			(start -1.9685 2.3622)
			(end 1.9685 -2.3622)
			(stroke
				(width 0)
				(type default)
			)
			(fill no)
			(layer "F.CrtYd")
		)
		(fp_poly
			(pts
				(xy -1.9685 -2.3622) (xy 1.9685 -2.3622) (xy 1.9685 2.3622) (xy -1.9685 2.3622)
			)
			(stroke
				(width 0)
				(type default)
			)
			(fill no)
			(layer "F.Fab")
		)
		(pad "1" smd rect
			(at -0.9525 1.3462 180)
			(size 0.5842 1.016)
			(layers "F.Cu" "F.Mask" "F.Paste")
			(net "P5V_STBY_BS")
		)
		(pad "2" smd rect
			(at 0 1.3462 180)
			(size 0.5842 1.016)
			(layers "F.Cu" "F.Mask" "F.Paste")
			(net "GND")
		)
		(pad "3" smd rect
			(at 0.9525 1.3462 180)
			(size 0.5842 1.016)
			(layers "F.Cu" "F.Mask" "F.Paste")
			(net "P5V_STBY_FB")
		)
		(pad "4" smd rect
			(at 0.9525 -1.3462 180)
			(size 0.5842 1.016)
			(layers "F.Cu" "F.Mask" "F.Paste")
			(net "P5V_STBY_EN")
		)
		(pad "5" smd rect
			(at 0 -1.3462 180)
			(size 0.5842 1.016)
			(layers "F.Cu" "F.Mask" "F.Paste")
			(net "P12V")
		)
		(pad "6" smd rect
			(at -0.9525 -1.3462 180)
			(size 0.5842 1.016)
			(layers "F.Cu" "F.Mask" "F.Paste")
			(net "P5V_STBY_LX")
		)
	)
	(footprint ""
		(layer "F.Cu")
		(at 39.0398 -186.5376)
		(property "Reference" "C701"
			(at 0 0 0)
			(layer "F.SilkS")
			(hide yes)
			(effects
				(font
					(size 1.27 1.27)
				)
			)
		)
		(property "Value" "SCD01U50V2KX-1GP"
			(at 1.1811 -2.7051 0)
			(unlocked yes)
			(layer "F.Fab")
			(hide yes)
			(effects
				(font
					(size 1.016 1.016)
					(thickness 0.1524)
				)
			)
		)
		(property "Device Type" "C402H22"
			(at 1.1811 -4.2291 0)
			(unlocked yes)
			(layer "F.Fab")
			(hide yes)
			(effects
				(font
					(size 1.016 1.016)
					(thickness 0.1524)
				)
			)
		)
		(duplicate_pad_numbers_are_jumpers no)
		(fp_rect
			(start -0.4318 0.9525)
			(end 0.4318 -0.9525)
			(stroke
				(width 0)
				(type default)
			)
			(fill no)
			(layer "F.CrtYd")
		)
		(fp_rect
			(start -0.4318 0.9525)
			(end 0.4318 -0.9525)
			(stroke
				(width 0)
				(type default)
			)
			(fill no)
			(layer "F.Fab")
		)
		(pad "1" smd custom
			(at 0 -0.4445)
			(size 0.1524 0.1524)
			(layers "F.Cu" "F.Mask" "F.Paste")
			(net "P3V3_STBY")
			(options
				(clearance outline)
				(anchor circle)
			)
			(primitives
				(gr_poly
					(pts
						(arc
							(start 0.3048 -0.2032)
							(mid 0.275042 -0.275042)
							(end 0.2032 -0.3048)
						)
						(arc
							(start -0.2032 -0.3048)
							(mid -0.275042 -0.275042)
							(end -0.3048 -0.2032)
						)
						(arc
							(start -0.3048 0.2032)
							(mid -0.275042 0.275042)
							(end -0.2032 0.3048)
						)
						(arc
							(start 0.2032 0.3048)
							(mid 0.275042 0.275042)
							(end 0.3048 0.2032)
						)
					)
					(width 0)
					(fill yes)
				)
			)
		)
		(pad "2" smd custom
			(at 0 0.4445)
			(size 0.1524 0.1524)
			(layers "F.Cu" "F.Mask" "F.Paste")
			(net "GND")
			(options
				(clearance outline)
				(anchor circle)
			)
			(primitives
				(gr_poly
					(pts
						(arc
							(start 0.3048 -0.2032)
							(mid 0.275042 -0.275042)
							(end 0.2032 -0.3048)
						)
						(arc
							(start -0.2032 -0.3048)
							(mid -0.275042 -0.275042)
							(end -0.3048 -0.2032)
						)
						(arc
							(start -0.3048 0.2032)
							(mid -0.275042 0.275042)
							(end -0.2032 0.3048)
						)
						(arc
							(start 0.2032 0.3048)
							(mid 0.275042 0.275042)
							(end 0.3048 0.2032)
						)
					)
					(width 0)
					(fill yes)
				)
			)
		)
	)
	(footprint ""
		(layer "F.Cu")
		(at 167.706802 -59.082432)
		(property "Reference" "PC94"
			(at 0 0 0)
			(layer "F.SilkS")
			(hide yes)
			(effects
				(font
					(size 1.27 1.27)
				)
			)
		)
		(property "Value" "SC4D7U16V5KX-1-GP"
			(at -0.0762 -6.1214 0)
			(unlocked yes)
			(layer "F.Fab")
			(hide yes)
			(effects
				(font
					(size 1.016 1.016)
					(thickness 0.1524)
				)
			)
		)
		(property "Device Type" "C805H56"
			(at -0.0762 -8.1534 0)
			(unlocked yes)
			(layer "F.Fab")
			(hide yes)
			(effects
				(font
					(size 1.016 1.016)
					(thickness 0.1524)
				)
			)
		)
		(duplicate_pad_numbers_are_jumpers no)
		(fp_line
			(start 0.635 0)
			(end -0.635 0)
			(stroke
				(width 0.508)
				(type default)
			)
			(layer "F.SilkS")
		)
		(fp_rect
			(start -0.9652 1.778)
			(end 0.9652 -1.778)
			(stroke
				(width 0)
				(type default)
			)
			(fill no)
			(layer "F.CrtYd")
		)
		(fp_poly
			(pts
				(xy -0.9652 -1.778) (xy 0.9652 -1.778) (xy 0.9652 1.778) (xy -0.9652 1.778)
			)
			(stroke
				(width 0)
				(type default)
			)
			(fill no)
			(layer "F.Fab")
		)
		(pad "1" smd rect
			(at 0 -0.9652)
			(size 1.397 1.143)
			(layers "F.Cu" "F.Mask" "F.Paste")
			(net "P0V9")
		)
		(pad "2" smd rect
			(at 0 0.9652)
			(size 1.397 1.143)
			(layers "F.Cu" "F.Mask" "F.Paste")
			(net "GND")
		)
	)
	(footprint ""
		(layer "F.Cu")
		(at 151.527002 -75.948032 90)
		(property "Reference" "PC213"
			(at 0 0 90)
			(layer "F.SilkS")
			(hide yes)
			(effects
				(font
					(size 1.27 1.27)
				)
			)
		)
		(property "Value" "SC22U25V6KX-GP-U"
			(at -2.860802 -5.279644 90)
			(unlocked yes)
			(layer "F.Fab")
			(hide yes)
			(effects
				(font
					(size 1.016 1.016)
					(thickness 0.1524)
				)
			)
		)
		(property "Device Type" "C1206-TO0D3H75"
			(at -2.860802 -6.803644 90)
			(unlocked yes)
			(layer "F.Fab")
			(hide yes)
			(effects
				(font
					(size 1.016 1.016)
					(thickness 0.1524)
				)
			)
		)
		(duplicate_pad_numbers_are_jumpers no)
		(fp_line
			(start 1.3081 -2.3749)
			(end 1.3081 2.3749)
			(stroke
				(width 0.1524)
				(type default)
			)
			(layer "F.SilkS")
		)
		(fp_line
			(start -1.3081 -2.3749)
			(end 1.3081 -2.3749)
			(stroke
				(width 0.1524)
				(type default)
			)
			(layer "F.SilkS")
		)
		(fp_line
			(start 1.3081 2.3749)
			(end -1.3081 2.3749)
			(stroke
				(width 0.1524)
				(type default)
			)
			(layer "F.SilkS")
		)
		(fp_line
			(start -1.3081 2.3749)
			(end -1.3081 -2.3749)
			(stroke
				(width 0.1524)
				(type default)
			)
			(layer "F.SilkS")
		)
		(fp_rect
			(start -0.8001 1.6002)
			(end 0.8001 -1.6002)
			(stroke
				(width 0)
				(type default)
			)
			(fill no)
			(layer "F.CrtYd")
		)
		(fp_poly
			(pts
				(xy -1.5621 2.4511) (xy -1.5621 1.6002) (xy 0.8001 1.6002) (xy 0.8001 -1.6002) (xy -0.8001 -1.6002)
				(xy -0.8001 1.5875) (xy -1.5621 1.5875) (xy -1.5621 -2.4511) (xy 1.5621 -2.4511) (xy 1.5621 2.4511)
			)
			(stroke
				(width 0)
				(type default)
			)
			(fill no)
			(layer "F.CrtYd")
		)
		(fp_rect
			(start -1.5621 2.4511)
			(end 1.5621 -2.4511)
			(stroke
				(width 0)
				(type default)
			)
			(fill no)
			(layer "F.Fab")
		)
		(pad "1" smd rect
			(at 0 -1.392936 90)
			(size 2.1082 1.4478)
			(layers "F.Cu" "F.Mask" "F.Paste")
			(net "P0V9_VIN")
		)
		(pad "2" smd rect
			(at 0 1.392936 90)
			(size 2.1082 1.4478)
			(layers "F.Cu" "F.Mask" "F.Paste")
			(net "GND")
		)
	)
	(footprint ""
		(layer "F.Cu")
		(at 225.17608 -3.810508 180)
		(property "Reference" "R175"
			(at 0 0 180)
			(layer "F.SilkS")
			(hide yes)
			(effects
				(font
					(size 1.27 1.27)
				)
			)
		)
		(property "Value" "4K7R2F-GP"
			(at 0.064008 -3.993896 180)
			(unlocked yes)
			(layer "F.Fab")
			(hide yes)
			(effects
				(font
					(size 1.016 1.016)
					(thickness 0.1524)
				)
			)
		)
		(property "Device Type" "R402H16"
			(at 0.064008 -5.517896 180)
			(unlocked yes)
			(layer "F.Fab")
			(hide yes)
			(effects
				(font
					(size 1.016 1.016)
					(thickness 0.1524)
				)
			)
		)
		(duplicate_pad_numbers_are_jumpers no)
		(fp_line
			(start 0.508 -0.9398)
			(end -0.508 -0.9398)
			(stroke
				(width 0.1524)
				(type default)
			)
			(layer "F.SilkS")
		)
		(fp_line
			(start -0.508 -0.9398)
			(end -0.508 0.9398)
			(stroke
				(width 0.1524)
				(type default)
			)
			(layer "F.SilkS")
		)
		(fp_rect
			(start -0.508 0.9398)
			(end 0.508 -0.9398)
			(stroke
				(width 0)
				(type default)
			)
			(fill no)
			(layer "F.CrtYd")
		)
		(fp_rect
			(start -0.508 0.9398)
			(end 0.508 -0.9398)
			(stroke
				(width 0)
				(type default)
			)
			(fill no)
			(layer "F.Fab")
		)
		(pad "1" smd custom
			(at 0 -0.4445 180)
			(size 0.1397 0.1397)
			(layers "F.Cu" "F.Mask" "F.Paste")
			(net "P3V3_STBY")
			(options
				(clearance outline)
				(anchor circle)
			)
			(primitives
				(gr_poly
					(pts
						(arc
							(start -0.1778 -0.2794)
							(mid -0.249642 -0.249642)
							(end -0.2794 -0.1778)
						)
						(arc
							(start -0.2794 0.1778)
							(mid -0.249642 0.249642)
							(end -0.1778 0.2794)
						)
						(arc
							(start 0.1778 0.2794)
							(mid 0.249642 0.249642)
							(end 0.2794 0.1778)
						)
						(arc
							(start 0.2794 -0.1778)
							(mid 0.249642 -0.249642)
							(end 0.1778 -0.2794)
						)
					)
					(width 0)
					(fill yes)
				)
			)
		)
		(pad "2" smd custom
			(at 0 0.4445 180)
			(size 0.1397 0.1397)
			(layers "F.Cu" "F.Mask" "F.Paste")
			(net "UART_SWITCH_R")
			(options
				(clearance outline)
				(anchor circle)
			)
			(primitives
				(gr_poly
					(pts
						(arc
							(start -0.1778 -0.2794)
							(mid -0.249642 -0.249642)
							(end -0.2794 -0.1778)
						)
						(arc
							(start -0.2794 0.1778)
							(mid -0.249642 0.249642)
							(end -0.1778 0.2794)
						)
						(arc
							(start 0.1778 0.2794)
							(mid 0.249642 0.249642)
							(end 0.2794 0.1778)
						)
						(arc
							(start 0.2794 -0.1778)
							(mid 0.249642 -0.249642)
							(end 0.1778 -0.2794)
						)
					)
					(width 0)
					(fill yes)
				)
			)
		)
	)
	(footprint ""
		(layer "F.Cu")
		(at 171.389802 -60.860432)
		(property "Reference" "PTC8"
			(at 0 0 0)
			(layer "F.SilkS")
			(hide yes)
			(effects
				(font
					(size 1.27 1.27)
				)
			)
		)
		(property "Value" "SE470UF2VDM-GP"
			(at 0 -9.6012 0)
			(unlocked yes)
			(layer "F.Fab")
			(hide yes)
			(effects
				(font
					(size 1.016 1.016)
					(thickness 0.1524)
				)
			)
		)
		(property "Device Type" "CT7343H83"
			(at 0 -11.1252 0)
			(unlocked yes)
			(layer "F.Fab")
			(hide yes)
			(effects
				(font
					(size 1.016 1.016)
					(thickness 0.1524)
				)
			)
		)
		(duplicate_pad_numbers_are_jumpers no)
		(fp_line
			(start -2.286 -4.8768)
			(end -2.286 -2.032)
			(stroke
				(width 0.1524)
				(type default)
			)
			(layer "F.SilkS")
		)
		(fp_line
			(start -2.286 4.8768)
			(end -2.286 2.032)
			(stroke
				(width 0.1524)
				(type default)
			)
			(layer "F.SilkS")
		)
		(fp_line
			(start 2.1082 -4.699)
			(end -2.1082 -4.699)
			(stroke
				(width 0.508)
				(type default)
			)
			(layer "F.SilkS")
		)
		(fp_line
			(start 2.286 -4.8768)
			(end -2.286 -4.8768)
			(stroke
				(width 0.1524)
				(type default)
			)
			(layer "F.SilkS")
		)
		(fp_line
			(start 2.286 -2.032)
			(end 2.286 -4.8768)
			(stroke
				(width 0.1524)
				(type default)
			)
			(layer "F.SilkS")
		)
		(fp_line
			(start 2.286 2.032)
			(end 2.286 4.8768)
			(stroke
				(width 0.1524)
				(type default)
			)
			(layer "F.SilkS")
		)
		(fp_line
			(start 2.286 4.8768)
			(end -2.286 4.8768)
			(stroke
				(width 0.1524)
				(type default)
			)
			(layer "F.SilkS")
		)
		(fp_rect
			(start -2.1463 3.6449)
			(end 2.1463 -3.6449)
			(stroke
				(width 0)
				(type default)
			)
			(fill no)
			(layer "F.CrtYd")
		)
		(fp_poly
			(pts
				(xy -2.54 4.953) (xy -2.54 4.2926) (xy -3.81 4.2926) (xy -3.81 -4.2926) (xy -2.54 -4.2926) (xy -2.54 -4.953)
				(xy 2.54 -4.953) (xy 2.54 -4.2926) (xy 3.81 -4.2926) (xy 3.81 -1.6256) (xy 2.1463 -1.6256) (xy 2.1463 -3.6449)
				(xy -2.1463 -3.6449) (xy -2.1463 3.6449) (xy 2.1463 3.6449) (xy 2.1463 -1.6129) (xy 3.81 -1.6129)
				(xy 3.81 4.2926) (xy 2.54 4.2926) (xy 2.54 4.953)
			)
			(stroke
				(width 0)
				(type default)
			)
			(fill no)
			(layer "F.CrtYd")
		)
		(fp_rect
			(start -3.81 4.2926)
			(end -2.54 -4.2926)
			(stroke
				(width 0)
				(type default)
			)
			(fill no)
			(layer "F.Fab")
		)
		(fp_rect
			(start -2.54 4.953)
			(end 2.54 -4.953)
			(stroke
				(width 0)
				(type default)
			)
			(fill no)
			(layer "F.Fab")
		)
		(fp_rect
			(start 2.54 4.2926)
			(end 3.81 -4.2926)
			(stroke
				(width 0)
				(type default)
			)
			(fill no)
			(layer "F.Fab")
		)
		(pad "1" smd rect
			(at 0 -3.1496)
			(size 2.413 2.286)
			(layers "F.Cu" "F.Mask" "F.Paste")
			(net "P0V9")
		)
		(pad "2" smd rect
			(at 0 3.1496)
			(size 2.413 2.286)
			(layers "F.Cu" "F.Mask" "F.Paste")
			(net "GND")
		)
		(zone
			(layer "F.Cu")
			(hatch none 0.5)
			(connect_pads
				(clearance 0)
			)
			(min_thickness 0.25)
			(keepout
				(tracks allowed)
				(vias not_allowed)
				(pads allowed)
				(copperpour not_allowed)
				(footprints allowed)
			)
			(placement
				(enabled no)
				(sheetname "")
			)
			(fill
				(thermal_gap 0.5)
				(thermal_bridge_width 0.5)
				(island_removal_mode 0)
			)
			(polygon
				(pts
					(xy 169.878502 -56.263032) (xy 172.901102 -56.263032) (xy 172.901102 -59.158632) (xy 172.901102 -59.488832)
					(xy 169.878502 -59.488832) (xy 169.878502 -59.158632)
				)
			)
		)
		(zone
			(layer "F.Cu")
			(hatch none 0.5)
			(connect_pads
				(clearance 0)
			)
			(min_thickness 0.25)
			(keepout
				(tracks allowed)
				(vias not_allowed)
				(pads allowed)
				(copperpour not_allowed)
				(footprints allowed)
			)
			(placement
				(enabled no)
				(sheetname "")
			)
			(fill
				(thermal_gap 0.5)
				(thermal_bridge_width 0.5)
				(island_removal_mode 0)
			)
			(polygon
				(pts
					(xy 172.901102 -62.549532) (xy 172.901102 -65.457832) (xy 169.878502 -65.457832) (xy 169.878502 -62.562232)
					(xy 169.878502 -62.232032) (xy 172.901102 -62.232032)
				)
			)
		)
	)
)
